(kicad_pcb
	(version 20260206)
	(generator "pcbnew")
	(generator_version "10.0")
	(general
		(thickness 1.6)
		(legacy_teardrops no)
	)
	(paper "A4")
	(title_block
		(title "03242023_DA0F0TMBIJ0_F0T_Motherboard_J_brd_V01_OCP.brd")
		(comment 1 "Grand Teton / footprint 3039 of 6105 (U2), pads 641-749 of 4677")
	)
	(layers
		(0 "F.Cu" signal "TOP")
		(4 "In1.Cu" signal "GND")
		(6 "In2.Cu" signal "IN1")
		(8 "In3.Cu" signal "GND1")
		(10 "In4.Cu" signal "IN2")
		(12 "In5.Cu" signal "GND2")
		(14 "In6.Cu" signal "IN3")
		(16 "In7.Cu" signal "GND3")
		(18 "In8.Cu" signal "VCC")
		(20 "In9.Cu" signal "VCC1")
		(22 "In10.Cu" signal "GND4")
		(24 "In11.Cu" signal "IN4")
		(26 "In12.Cu" signal "GND5")
		(28 "In13.Cu" signal "IN5")
		(30 "In14.Cu" signal "GND6")
		(32 "In15.Cu" signal "IN6")
		(34 "In16.Cu" signal "GND7")
		(2 "B.Cu" signal "BOTTOM")
		(9 "F.Adhes" user "F.Adhesive")
		(11 "B.Adhes" user "B.Adhesive")
		(13 "F.Paste" user "Package Geometry/Pastemask Top")
		(15 "B.Paste" user "Package Geometry/Pastemask Bottom")
		(5 "F.SilkS" user "Ref Des/Silkscreen Top")
		(7 "B.SilkS" user "Ref Des/Silkscreen Bottom")
		(1 "F.Mask" user "Board Geometry/Soldermask Top")
		(3 "B.Mask" user "Board Geometry/Soldermask Bottom")
		(17 "Dwgs.User" user "User.Drawings")
		(19 "Cmts.User" user "User.Comments")
		(21 "Eco1.User" user "User.Eco1")
		(23 "Eco2.User" user "User.Eco2")
		(25 "Edge.Cuts" user "Board Geometry/Outline")
		(27 "Margin" user)
		(31 "F.CrtYd" user "Package Geometry/Place Bound Top")
		(29 "B.CrtYd" user "Package Geometry/Place Bound Bottom")
		(35 "F.Fab" user "Ref Des/Assembly Top")
		(33 "B.Fab" user "Ref Des/Assembly Bottom")
	)
	(footprint ""
		(layer "F.Cu")
		(at 359.870248 -251.76988 90)
		(property "Reference" "U2"
			(at -74.416158 -44.488608 0)
			(unlocked yes)
			(layer "F.SilkS")
			(effects
				(font
					(size 1.6002 1.1938)
					(thickness 0.1524)
				)
				(justify left)
			)
		)
		(property "Value" ""
			(at 0 0 90)
			(layer "F.Fab")
			(effects
				(font
					(size 1.27 1.27)
				)
			)
		)
		(duplicate_pad_numbers_are_jumpers no)
		(pad "AP61" smd circle
			(at 13.008356 -11.457686 270)
			(size 0.4318 0.4318)
			(layers "F.Cu" "F.Mask" "F.Paste")
			(net "GND")
		)
		(pad "AP63" smd circle
			(at 14.635988 -11.457686 270)
			(size 0.4318 0.4318)
			(layers "F.Cu" "F.Mask" "F.Paste")
			(net "M_D_CPU0_SA_DQ<30>")
		)
		(pad "AP65" smd circle
			(at 16.263874 -11.457686 270)
			(size 0.4318 0.4318)
			(layers "F.Cu" "F.Mask" "F.Paste")
			(net "M_D_CPU0_SA_DQ<27>")
		)
		(pad "AP67" smd circle
			(at 17.89176 -11.457686 270)
			(size 0.4318 0.4318)
			(layers "F.Cu" "F.Mask" "F.Paste")
			(net "GND")
		)
		(pad "AP69" smd circle
			(at 19.519392 -11.457686 270)
			(size 0.4318 0.4318)
			(layers "F.Cu" "F.Mask" "F.Paste")
			(net "M_D_CPU0_SA_DQ<22>")
		)
		(pad "AP71" smd circle
			(at 21.147278 -11.457686 270)
			(size 0.4318 0.4318)
			(layers "F.Cu" "F.Mask" "F.Paste")
			(net "M_D_CPU0_SA_DQ<19>")
		)
		(pad "AP73" smd circle
			(at 22.77491 -11.457686 270)
			(size 0.4318 0.4318)
			(layers "F.Cu" "F.Mask" "F.Paste")
			(net "GND")
		)
		(pad "AP75" smd circle
			(at 24.402796 -11.457686 270)
			(size 0.4318 0.4318)
			(layers "F.Cu" "F.Mask" "F.Paste")
			(net "M_D_CPU0_SA_DQ<14>")
		)
		(pad "AP77" smd circle
			(at 26.030682 -11.457686 270)
			(size 0.4318 0.4318)
			(layers "F.Cu" "F.Mask" "F.Paste")
			(net "M_D_CPU0_SA_DQ<11>")
		)
		(pad "AP79" smd circle
			(at 27.658314 -11.457686 270)
			(size 0.4318 0.4318)
			(layers "F.Cu" "F.Mask" "F.Paste")
			(net "GND")
		)
		(pad "AP81" smd circle
			(at 29.2862 -11.457686 270)
			(size 0.4318 0.4318)
			(layers "F.Cu" "F.Mask" "F.Paste")
			(net "UPI_CPU0_CPU1_P2P2_DP<11>")
		)
		(pad "AP83" smd circle
			(at 30.914086 -11.457686 270)
			(size 0.4318 0.4318)
			(layers "F.Cu" "F.Mask" "F.Paste")
			(net "GND")
		)
		(pad "AP85" smd circle
			(at 32.541718 -11.457686 270)
			(size 0.4318 0.4318)
			(layers "F.Cu" "F.Mask" "F.Paste")
			(net "P5E_CPU0_PE4_TX_DN<11>")
		)
		(pad "AP87" smd circle
			(at 34.169604 -11.457686 270)
			(size 0.4318 0.4318)
			(layers "F.Cu" "F.Mask" "F.Paste")
			(net "GND")
		)
		(pad "AP89" smd circle
			(at 35.797236 -11.457686 270)
			(size 0.4318 0.4318)
			(layers "F.Cu" "F.Mask" "F.Paste")
			(net "P5E_CPU0_PE4_RX_DN<11>")
		)
		(pad "AP91" smd oval
			(at 37.425122 -11.457686)
			(size 0.381 0.4826)
			(drill
				(offset 0 -0.0508)
			)
			(layers "F.Cu" "F.Mask" "F.Paste")
			(net "GND")
		)
		(pad "AR1" smd oval
			(at -37.425122 -11.097514 180)
			(size 0.381 0.4826)
			(drill
				(offset 0 -0.0508)
			)
			(layers "F.Cu" "F.Mask" "F.Paste")
			(net "GND")
		)
		(pad "AR3" smd circle
			(at -35.797236 -11.097514 270)
			(size 0.4318 0.4318)
			(layers "F.Cu" "F.Mask" "F.Paste")
			(net "UPI_CPU0_CPU1_P0P1_DN<13>")
		)
		(pad "AR5" smd circle
			(at -34.169604 -11.097514 270)
			(size 0.4318 0.4318)
			(layers "F.Cu" "F.Mask" "F.Paste")
			(net "GND")
		)
		(pad "AR7" smd circle
			(at -32.541718 -11.097514 270)
			(size 0.4318 0.4318)
			(layers "F.Cu" "F.Mask" "F.Paste")
			(net "UPI_CPU1_CPU0_P1P0_DN<12>")
		)
		(pad "AR9" smd circle
			(at -30.914086 -11.097514 270)
			(size 0.4318 0.4318)
			(layers "F.Cu" "F.Mask" "F.Paste")
			(net "GND")
		)
		(pad "AR11" smd circle
			(at -29.2862 -11.097514 270)
			(size 0.4318 0.4318)
			(layers "F.Cu" "F.Mask" "F.Paste")
			(net "P5E_CPU0_PE0_RX_DP<12>")
		)
		(pad "AR13" smd circle
			(at -27.658314 -11.097514 270)
			(size 0.4318 0.4318)
			(layers "F.Cu" "F.Mask" "F.Paste")
			(net "GND")
		)
		(pad "AR15" smd circle
			(at -26.030682 -11.097514 270)
			(size 0.4318 0.4318)
			(layers "F.Cu" "F.Mask" "F.Paste")
			(net "P5E_CPU0_PE0_TX_DP<11>")
		)
		(pad "AR17" smd circle
			(at -24.402796 -11.097514 270)
			(size 0.4318 0.4318)
			(layers "F.Cu" "F.Mask" "F.Paste")
			(net "NC_CPU0_UPI0_APROBE<1>")
		)
		(pad "AR19" smd circle
			(at -22.77491 -11.097514 270)
			(size 0.4318 0.4318)
			(layers "F.Cu" "F.Mask" "F.Paste")
			(net "GND")
		)
		(pad "AR21" smd circle
			(at -21.147278 -11.097514 270)
			(size 0.4318 0.4318)
			(layers "F.Cu" "F.Mask" "F.Paste")
			(net "M_D_CPU0_SB_DQS_DP<8>")
		)
		(pad "AR23" smd circle
			(at -19.519392 -11.097514 270)
			(size 0.4318 0.4318)
			(layers "F.Cu" "F.Mask" "F.Paste")
			(net "GND")
		)
		(pad "AR25" smd circle
			(at -17.89176 -11.097514 270)
			(size 0.4318 0.4318)
			(layers "F.Cu" "F.Mask" "F.Paste")
			(net "GND")
		)
		(pad "AR27" smd circle
			(at -16.263874 -11.097514 270)
			(size 0.4318 0.4318)
			(layers "F.Cu" "F.Mask" "F.Paste")
			(net "M_D_CPU0_SB_DQS_DP<6>")
		)
		(pad "AR29" smd circle
			(at -14.635988 -11.097514 270)
			(size 0.4318 0.4318)
			(layers "F.Cu" "F.Mask" "F.Paste")
			(net "GND")
		)
		(pad "AR31" smd circle
			(at -13.008356 -11.097514 270)
			(size 0.4318 0.4318)
			(layers "F.Cu" "F.Mask" "F.Paste")
			(net "GND")
		)
		(pad "AR33" smd circle
			(at -11.380724 -11.097514 270)
			(size 0.4318 0.4318)
			(layers "F.Cu" "F.Mask" "F.Paste")
			(net "M_D_CPU0_SB_DQS_DP<5>")
		)
		(pad "AR35" smd circle
			(at -9.752838 -11.097514 270)
			(size 0.4318 0.4318)
			(layers "F.Cu" "F.Mask" "F.Paste")
			(net "GND")
		)
		(pad "AR37" smd circle
			(at -8.124952 -11.097514 270)
			(size 0.4318 0.4318)
			(layers "F.Cu" "F.Mask" "F.Paste")
			(net "GND")
		)
		(pad "AR39" smd circle
			(at -6.49732 -11.097514 270)
			(size 0.4318 0.4318)
			(layers "F.Cu" "F.Mask" "F.Paste")
			(net "M_D_CPU0_SB_DQS_DN<4>")
		)
		(pad "AR41" smd circle
			(at -4.869434 -11.097514 270)
			(size 0.4318 0.4318)
			(layers "F.Cu" "F.Mask" "F.Paste")
			(net "GND")
		)
		(pad "AR43" smd circle
			(at -3.241802 -11.097514 270)
			(size 0.4318 0.4318)
			(layers "F.Cu" "F.Mask" "F.Paste")
			(net "GND")
		)
		(pad "AR45" smd circle
			(at -1.613916 -11.097514 270)
			(size 0.4318 0.4318)
			(layers "F.Cu" "F.Mask" "F.Paste")
			(net "M_D_CPU0_CLK_DP<1>")
		)
		(pad "AR48" smd circle
			(at 2.427732 -10.987532 270)
			(size 0.4318 0.4318)
			(layers "F.Cu" "F.Mask" "F.Paste")
			(net "GND")
		)
		(pad "AR50" smd circle
			(at 4.055618 -10.987532 270)
			(size 0.4318 0.4318)
			(layers "F.Cu" "F.Mask" "F.Paste")
			(net "GND")
		)
		(pad "AR52" smd circle
			(at 5.68325 -10.987532 270)
			(size 0.4318 0.4318)
			(layers "F.Cu" "F.Mask" "F.Paste")
			(net "M_D_CPU0_SA_CA<1>")
		)
		(pad "AR54" smd circle
			(at 7.311136 -10.987532 270)
			(size 0.4318 0.4318)
			(layers "F.Cu" "F.Mask" "F.Paste")
			(net "GND")
		)
		(pad "AR56" smd circle
			(at 8.939022 -10.987532 270)
			(size 0.4318 0.4318)
			(layers "F.Cu" "F.Mask" "F.Paste")
			(net "GND")
		)
		(pad "AR58" smd circle
			(at 10.566654 -10.987532 270)
			(size 0.4318 0.4318)
			(layers "F.Cu" "F.Mask" "F.Paste")
			(net "M_D_CPU0_SA_DQS_DP<9>")
		)
		(pad "AR60" smd circle
			(at 12.19454 -10.987532 270)
			(size 0.4318 0.4318)
			(layers "F.Cu" "F.Mask" "F.Paste")
			(net "GND")
		)
		(pad "AR62" smd circle
			(at 13.822426 -10.987532 270)
			(size 0.4318 0.4318)
			(layers "F.Cu" "F.Mask" "F.Paste")
			(net "GND")
		)
		(pad "AR64" smd circle
			(at 15.450058 -10.987532 270)
			(size 0.4318 0.4318)
			(layers "F.Cu" "F.Mask" "F.Paste")
			(net "M_D_CPU0_SA_DQS_DP<8>")
		)
		(pad "AR66" smd circle
			(at 17.07769 -10.987532 270)
			(size 0.4318 0.4318)
			(layers "F.Cu" "F.Mask" "F.Paste")
			(net "GND")
		)
		(pad "AR68" smd circle
			(at 18.705576 -10.987532 270)
			(size 0.4318 0.4318)
			(layers "F.Cu" "F.Mask" "F.Paste")
			(net "GND")
		)
		(pad "AR70" smd circle
			(at 20.333462 -10.987532 270)
			(size 0.4318 0.4318)
			(layers "F.Cu" "F.Mask" "F.Paste")
			(net "M_D_CPU0_SA_DQS_DP<7>")
		)
		(pad "AR72" smd circle
			(at 21.961094 -10.987532 270)
			(size 0.4318 0.4318)
			(layers "F.Cu" "F.Mask" "F.Paste")
			(net "GND")
		)
		(pad "AR74" smd circle
			(at 23.58898 -10.987532 270)
			(size 0.4318 0.4318)
			(layers "F.Cu" "F.Mask" "F.Paste")
			(net "GND")
		)
		(pad "AR76" smd circle
			(at 25.216612 -10.987532 270)
			(size 0.4318 0.4318)
			(layers "F.Cu" "F.Mask" "F.Paste")
			(net "M_D_CPU0_SA_DQS_DP<6>")
		)
		(pad "AR78" smd circle
			(at 26.844498 -10.987532 270)
			(size 0.4318 0.4318)
			(layers "F.Cu" "F.Mask" "F.Paste")
			(net "GND")
		)
		(pad "AR80" smd circle
			(at 28.472384 -10.987532 270)
			(size 0.4318 0.4318)
			(layers "F.Cu" "F.Mask" "F.Paste")
			(net "UPI_CPU0_CPU1_P2P2_DN<9>")
		)
		(pad "AR82" smd circle
			(at 30.100016 -10.987532 270)
			(size 0.4318 0.4318)
			(layers "F.Cu" "F.Mask" "F.Paste")
			(net "GND")
		)
		(pad "AR84" smd circle
			(at 31.727902 -10.987532 270)
			(size 0.4318 0.4318)
			(layers "F.Cu" "F.Mask" "F.Paste")
			(net "GND")
		)
		(pad "AR86" smd circle
			(at 33.355534 -10.987532 270)
			(size 0.4318 0.4318)
			(layers "F.Cu" "F.Mask" "F.Paste")
			(net "P5E_CPU0_PE4_TX_DN<12>")
		)
		(pad "AR88" smd circle
			(at 34.98342 -10.987532 270)
			(size 0.4318 0.4318)
			(layers "F.Cu" "F.Mask" "F.Paste")
			(net "GND")
		)
		(pad "AR90" smd circle
			(at 36.611306 -10.987532 270)
			(size 0.4318 0.4318)
			(layers "F.Cu" "F.Mask" "F.Paste")
			(net "P5E_CPU0_PE4_RX_DP<12>")
		)
		(pad "AT2" smd circle
			(at -36.611306 -10.627868 270)
			(size 0.4318 0.4318)
			(layers "F.Cu" "F.Mask" "F.Paste")
			(net "UPI_CPU0_CPU1_P0P1_DP<13>")
		)
		(pad "AT4" smd circle
			(at -34.98342 -10.627868 270)
			(size 0.4318 0.4318)
			(layers "F.Cu" "F.Mask" "F.Paste")
			(net "GND")
		)
		(pad "AT6" smd circle
			(at -33.355534 -10.627868 270)
			(size 0.4318 0.4318)
			(layers "F.Cu" "F.Mask" "F.Paste")
			(net "UPI_CPU1_CPU0_P1P0_DN<13>")
		)
		(pad "AT8" smd circle
			(at -31.727902 -10.627868 270)
			(size 0.4318 0.4318)
			(layers "F.Cu" "F.Mask" "F.Paste")
			(net "GND")
		)
		(pad "AT10" smd circle
			(at -30.100016 -10.627868 270)
			(size 0.4318 0.4318)
			(layers "F.Cu" "F.Mask" "F.Paste")
			(net "P5E_CPU0_PE0_RX_DP<13>")
		)
		(pad "AT12" smd circle
			(at -28.472384 -10.627868 270)
			(size 0.4318 0.4318)
			(layers "F.Cu" "F.Mask" "F.Paste")
			(net "GND")
		)
		(pad "AT14" smd circle
			(at -26.844498 -10.627868 270)
			(size 0.4318 0.4318)
			(layers "F.Cu" "F.Mask" "F.Paste")
			(net "P5E_CPU0_PE0_TX_DP<12>")
		)
		(pad "AT16" smd circle
			(at -25.216612 -10.627868 270)
			(size 0.4318 0.4318)
			(layers "F.Cu" "F.Mask" "F.Paste")
			(net "GND")
		)
		(pad "AT18" smd circle
			(at -23.58898 -10.627868 270)
			(size 0.4318 0.4318)
			(layers "F.Cu" "F.Mask" "F.Paste")
			(net "PD_CPU0_BIST_ENABLE")
		)
		(pad "AT20" smd circle
			(at -21.961094 -10.627868 270)
			(size 0.4318 0.4318)
			(layers "F.Cu" "F.Mask" "F.Paste")
			(net "GND")
		)
		(pad "AT22" smd circle
			(at -20.333462 -10.627868 270)
			(size 0.4318 0.4318)
			(layers "F.Cu" "F.Mask" "F.Paste")
			(net "GND")
		)
		(pad "AT24" smd circle
			(at -18.705576 -10.627868 270)
			(size 0.4318 0.4318)
			(layers "F.Cu" "F.Mask" "F.Paste")
			(net "NC_CPU0_VIEWPIN_DIE00<1>")
		)
		(pad "AT26" smd circle
			(at -17.07769 -10.627868 270)
			(size 0.4318 0.4318)
			(layers "F.Cu" "F.Mask" "F.Paste")
			(net "GND")
		)
		(pad "AT28" smd circle
			(at -15.450058 -10.627868 270)
			(size 0.4318 0.4318)
			(layers "F.Cu" "F.Mask" "F.Paste")
			(net "GND")
		)
		(pad "AT30" smd circle
			(at -13.822426 -10.627868 270)
			(size 0.4318 0.4318)
			(layers "F.Cu" "F.Mask" "F.Paste")
			(net "CLK_100M_DB2000_CPU0_BCLK0_DN")
		)
		(pad "AT32" smd circle
			(at -12.19454 -10.627868 270)
			(size 0.4318 0.4318)
			(layers "F.Cu" "F.Mask" "F.Paste")
			(net "GND")
		)
		(pad "AT34" smd circle
			(at -10.566654 -10.627868 270)
			(size 0.4318 0.4318)
			(layers "F.Cu" "F.Mask" "F.Paste")
			(net "GND")
		)
		(pad "AT36" smd circle
			(at -8.939022 -10.627868 270)
			(size 0.4318 0.4318)
			(layers "F.Cu" "F.Mask" "F.Paste")
			(net "PVCCD_HV_CPU0")
		)
		(pad "AT38" smd circle
			(at -7.311136 -10.627868 270)
			(size 0.4318 0.4318)
			(layers "F.Cu" "F.Mask" "F.Paste")
			(net "GND")
		)
		(pad "AT40" smd circle
			(at -5.68325 -10.627868 270)
			(size 0.4318 0.4318)
			(layers "F.Cu" "F.Mask" "F.Paste")
			(net "GND")
		)
		(pad "AT42" smd circle
			(at -4.055618 -10.627868 270)
			(size 0.4318 0.4318)
			(layers "F.Cu" "F.Mask" "F.Paste")
			(net "M_A_CPU0_SA_RSP<0>")
		)
		(pad "AT44" smd circle
			(at -2.427732 -10.627868 270)
			(size 0.4318 0.4318)
			(layers "F.Cu" "F.Mask" "F.Paste")
			(net "GND")
		)
		(pad "AT47" smd circle
			(at 1.613916 -10.517886 270)
			(size 0.4318 0.4318)
			(layers "F.Cu" "F.Mask" "F.Paste")
			(net "M_C_CPU0_ALERT_N")
		)
		(pad "AT49" smd circle
			(at 3.241802 -10.517886 270)
			(size 0.4318 0.4318)
			(layers "F.Cu" "F.Mask" "F.Paste")
			(net "M_A_CPU0_ALERT_N")
		)
		(pad "AT51" smd circle
			(at 4.869434 -10.517886 270)
			(size 0.4318 0.4318)
			(layers "F.Cu" "F.Mask" "F.Paste")
			(net "GND")
		)
		(pad "AT53" smd circle
			(at 6.49732 -10.517886 270)
			(size 0.4318 0.4318)
			(layers "F.Cu" "F.Mask" "F.Paste")
			(net "GND")
		)
		(pad "AT55" smd circle
			(at 8.124952 -10.517886 270)
			(size 0.4318 0.4318)
			(layers "F.Cu" "F.Mask" "F.Paste")
			(net "PVCCD_HV_CPU0")
		)
		(pad "AT57" smd circle
			(at 9.752838 -10.517886 270)
			(size 0.4318 0.4318)
			(layers "F.Cu" "F.Mask" "F.Paste")
			(net "GND")
		)
		(pad "AT59" smd circle
			(at 11.380724 -10.517886 270)
			(size 0.4318 0.4318)
			(layers "F.Cu" "F.Mask" "F.Paste")
			(net "GND")
		)
		(pad "AT61" smd circle
			(at 13.008356 -10.517886 270)
			(size 0.4318 0.4318)
			(layers "F.Cu" "F.Mask" "F.Paste")
			(net "PVCCFA_EHV_CPU0")
		)
		(pad "AT63" smd circle
			(at 14.635988 -10.517886 270)
			(size 0.4318 0.4318)
			(layers "F.Cu" "F.Mask" "F.Paste")
			(net "GND")
		)
		(pad "AT65" smd circle
			(at 16.263874 -10.517886 270)
			(size 0.4318 0.4318)
			(layers "F.Cu" "F.Mask" "F.Paste")
			(net "GND")
		)
		(pad "AT67" smd circle
			(at 17.89176 -10.517886 270)
			(size 0.4318 0.4318)
			(layers "F.Cu" "F.Mask" "F.Paste")
			(net "NC_CPU0_UPI2_APROBE<1>")
		)
		(pad "AT69" smd circle
			(at 19.519392 -10.517886 270)
			(size 0.4318 0.4318)
			(layers "F.Cu" "F.Mask" "F.Paste")
			(net "GND")
		)
		(pad "AT71" smd circle
			(at 21.147278 -10.517886 270)
			(size 0.4318 0.4318)
			(layers "F.Cu" "F.Mask" "F.Paste")
			(net "GND")
		)
		(pad "AT73" smd circle
			(at 22.77491 -10.517886 270)
			(size 0.4318 0.4318)
			(layers "F.Cu" "F.Mask" "F.Paste")
			(net "PVCCFA_EHV_FIVRA_CPU0")
		)
		(pad "AT75" smd circle
			(at 24.402796 -10.517886 270)
			(size 0.4318 0.4318)
			(layers "F.Cu" "F.Mask" "F.Paste")
			(net "GND")
		)
		(pad "AT77" smd circle
			(at 26.030682 -10.517886 270)
			(size 0.4318 0.4318)
			(layers "F.Cu" "F.Mask" "F.Paste")
			(net "GND")
		)
		(pad "AT79" smd circle
			(at 27.658314 -10.517886 270)
			(size 0.4318 0.4318)
			(layers "F.Cu" "F.Mask" "F.Paste")
			(net "GND")
		)
		(pad "AT81" smd circle
			(at 29.2862 -10.517886 270)
			(size 0.4318 0.4318)
			(layers "F.Cu" "F.Mask" "F.Paste")
			(net "UPI_CPU0_CPU1_P2P2_DP<9>")
		)
		(pad "AT83" smd circle
			(at 30.914086 -10.517886 270)
			(size 0.4318 0.4318)
			(layers "F.Cu" "F.Mask" "F.Paste")
			(net "UPI_CPU0_CPU1_P2P2_DN<8>")
		)
		(pad "AT85" smd circle
			(at 32.541718 -10.517886 270)
			(size 0.4318 0.4318)
			(layers "F.Cu" "F.Mask" "F.Paste")
			(net "VSENSE_PVCCFA_EHV_FIVRA_CPU0_DN")
		)
		(pad "AT87" smd circle
			(at 34.169604 -10.517886 270)
			(size 0.4318 0.4318)
			(layers "F.Cu" "F.Mask" "F.Paste")
			(net "P5E_CPU0_PE4_TX_DP<12>")
		)
		(pad "AT89" smd circle
			(at 35.797236 -10.517886 270)
			(size 0.4318 0.4318)
			(layers "F.Cu" "F.Mask" "F.Paste")
			(net "PVCCFA_EHV_FIVRA_CPU0")
		)
		(pad "AT91" smd oval
			(at 37.425122 -10.517886)
			(size 0.381 0.4826)
			(drill
				(offset 0 -0.0508)
			)
			(layers "F.Cu" "F.Mask" "F.Paste")
			(net "P5E_CPU0_PE4_RX_DN<12>")
		)
		(pad "AU1" smd oval
			(at -37.425122 -10.157714 180)
			(size 0.381 0.4826)
			(drill
				(offset 0 -0.0508)
			)
			(layers "F.Cu" "F.Mask" "F.Paste")
			(net "UPI_CPU0_CPU1_P0P1_DN<14>")
		)
		(pad "AU3" smd circle
			(at -35.797236 -10.157714 270)
			(size 0.4318 0.4318)
			(layers "F.Cu" "F.Mask" "F.Paste")
			(net "PVCCD_HV_CPU0")
		)
		(pad "AU5" smd circle
			(at -34.169604 -10.157714 270)
			(size 0.4318 0.4318)
			(layers "F.Cu" "F.Mask" "F.Paste")
			(net "UPI_CPU1_CPU0_P1P0_DP<13>")
		)
	)
)
